# SCM (Grand Teton) — schematic netlist excerpt (pin names and nets, part order shuffled) for the footprints in the layout excerpt that follows; sources: Cadence DE-HDL packaged netlist, KiCad conversion of 12092022_DA0F0TMDCD0_F0T_Management_Board_D_brd_V3_OCP.brd

R6  Q_RES  240 1% CHIP  pkg 0402LF  page 20 : A = PD_M_BMC_DDR4_ZQ ; B = GND
C194  Q_CAP  10UF 16V 20% X6S  pkg C0603  page 41 : A = P3V3_AUX ; B = GND

(kicad_pcb
	(version 20260206)
	(generator "pcbnew")
	(generator_version "10.0")
	(general
		(thickness 1.6)
		(legacy_teardrops no)
	)
	(paper "A4")
	(title_block
		(title "12092022_DA0F0TMDCD0_F0T_Management_Board_D_brd_V3_OCP.brd")
		(comment 1 "Grand Teton / footprints 1233-1234 of 1440")
	)
	(layers
		(0 "F.Cu" signal "TOP")
		(4 "In1.Cu" signal "GND")
		(6 "In2.Cu" signal "IN1")
		(8 "In3.Cu" signal "GND1")
		(10 "In4.Cu" signal "IN2")
		(12 "In5.Cu" signal "VCC")
		(14 "In6.Cu" signal "VCC1")
		(16 "In7.Cu" signal "IN3")
		(18 "In8.Cu" signal "GND2")
		(20 "In9.Cu" signal "IN4")
		(22 "In10.Cu" signal "GND3")
		(2 "B.Cu" signal "BOTTOM")
		(9 "F.Adhes" user "F.Adhesive")
		(11 "B.Adhes" user "B.Adhesive")
		(13 "F.Paste" user "Package Geometry/Pastemask Top")
		(15 "B.Paste" user "Package Geometry/Pastemask Bottom")
		(5 "F.SilkS" user "Ref Des/Silkscreen Top")
		(7 "B.SilkS" user "Ref Des/Silkscreen Bottom")
		(1 "F.Mask" user "Board Geometry/Soldermask Top")
		(3 "B.Mask" user "Board Geometry/Soldermask Bottom")
		(17 "Dwgs.User" user "User.Drawings")
		(19 "Cmts.User" user "User.Comments")
		(21 "Eco1.User" user "User.Eco1")
		(23 "Eco2.User" user "User.Eco2")
		(25 "Edge.Cuts" user "Board Geometry/Outline")
		(27 "Margin" user)
		(31 "F.CrtYd" user "Package Geometry/Place Bound Top")
		(29 "B.CrtYd" user "Package Geometry/Place Bound Bottom")
		(35 "F.Fab" user "Ref Des/Assembly Top")
		(33 "B.Fab" user "Ref Des/Assembly Bottom")
	)
	(footprint ""
		(layer "B.Cu")
		(at 29.972 -102.108 180)
		(property "Reference" "C194"
			(at 0 0 0)
			(layer "B.SilkS")
			(hide yes)
			(effects
				(font
					(size 1.27 1.27)
				)
				(justify mirror)
			)
		)
		(property "Value" ""
			(at 0 0 0)
			(layer "B.Fab")
			(effects
				(font
					(size 1.27 1.27)
				)
				(justify mirror)
			)
		)
		(duplicate_pad_numbers_are_jumpers no)
		(fp_line
			(start 1.2954 0.5842)
			(end 1.2954 -0.5842)
			(stroke
				(width 0.1524)
				(type default)
			)
			(layer "B.SilkS")
		)
		(fp_line
			(start 1.2954 -0.5842)
			(end -1.2954 -0.5842)
			(stroke
				(width 0.1524)
				(type default)
			)
			(layer "B.SilkS")
		)
		(fp_line
			(start 0 -0.5842)
			(end 0 0.5842)
			(stroke
				(width 0.1524)
				(type default)
			)
			(layer "B.SilkS")
		)
		(fp_line
			(start -1.2954 0.5842)
			(end 1.2954 0.5842)
			(stroke
				(width 0.1524)
				(type default)
			)
			(layer "B.SilkS")
		)
		(fp_line
			(start -1.2954 -0.5842)
			(end -1.2954 0.5842)
			(stroke
				(width 0.1524)
				(type default)
			)
			(layer "B.SilkS")
		)
		(fp_line
			(start 1.1938 0.4064)
			(end 1.1938 -0.4064)
			(stroke
				(width 0.1)
				(type default)
			)
			(layer "B.Fab")
		)
		(fp_line
			(start 1.1938 -0.4064)
			(end 0.8636 -0.4064)
			(stroke
				(width 0.1)
				(type default)
			)
			(layer "B.Fab")
		)
		(fp_line
			(start 0.8636 0.4572)
			(end 0.8636 0.4064)
			(stroke
				(width 0.1)
				(type default)
			)
			(layer "B.Fab")
		)
		(fp_line
			(start 0.8636 0.4064)
			(end 1.1938 0.4064)
			(stroke
				(width 0.1)
				(type default)
			)
			(layer "B.Fab")
		)
		(fp_line
			(start 0.8636 -0.4064)
			(end 0.8636 -0.4572)
			(stroke
				(width 0.1)
				(type default)
			)
			(layer "B.Fab")
		)
		(fp_line
			(start 0.8636 -0.4572)
			(end -0.8636 -0.4572)
			(stroke
				(width 0.1)
				(type default)
			)
			(layer "B.Fab")
		)
		(fp_line
			(start -0.8636 0.4572)
			(end 0.8636 0.4572)
			(stroke
				(width 0.1)
				(type default)
			)
			(layer "B.Fab")
		)
		(fp_line
			(start -0.8636 0.4064)
			(end -0.8636 0.4572)
			(stroke
				(width 0.1)
				(type default)
			)
			(layer "B.Fab")
		)
		(fp_line
			(start -0.8636 -0.4064)
			(end -1.1938 -0.4064)
			(stroke
				(width 0.1)
				(type default)
			)
			(layer "B.Fab")
		)
		(fp_line
			(start -0.8636 -0.4572)
			(end -0.8636 -0.4064)
			(stroke
				(width 0.1)
				(type default)
			)
			(layer "B.Fab")
		)
		(fp_line
			(start -1.1938 0.4064)
			(end -0.8636 0.4064)
			(stroke
				(width 0.1)
				(type default)
			)
			(layer "B.Fab")
		)
		(fp_line
			(start -1.1938 -0.4064)
			(end -1.1938 0.4064)
			(stroke
				(width 0.1)
				(type default)
			)
			(layer "B.Fab")
		)
		(pad "1" smd rect
			(at 0.7366 0 90)
			(size 0.7112 0.8128)
			(layers "B.Cu" "B.Mask" "B.Paste")
			(net "P3V3_AUX")
		)
		(pad "2" smd rect
			(at -0.7366 0 90)
			(size 0.7112 0.8128)
			(layers "B.Cu" "B.Mask" "B.Paste")
			(net "GND")
		)
	)
	(footprint ""
		(layer "B.Cu")
		(at 80.547464 -51.0413 -90)
		(property "Reference" "R6"
			(at 0 0 90)
			(layer "B.SilkS")
			(hide yes)
			(effects
				(font
					(size 1.27 1.27)
				)
				(justify mirror)
			)
		)
		(property "Value" ""
			(at 0 0 90)
			(layer "B.Fab")
			(effects
				(font
					(size 1.27 1.27)
				)
				(justify mirror)
			)
		)
		(duplicate_pad_numbers_are_jumpers no)
		(fp_line
			(start -0.7874 0.4064)
			(end 0.7874 0.4064)
			(stroke
				(width 0.1524)
				(type default)
			)
			(layer "B.SilkS")
		)
		(fp_line
			(start 0.7874 0.4064)
			(end 0.7874 -0.4064)
			(stroke
				(width 0.1524)
				(type default)
			)
			(layer "B.SilkS")
		)
		(fp_line
			(start -0.7874 -0.4064)
			(end -0.7874 0.4064)
			(stroke
				(width 0.1524)
				(type default)
			)
			(layer "B.SilkS")
		)
		(fp_line
			(start 0.7874 -0.4064)
			(end -0.7874 -0.4064)
			(stroke
				(width 0.1524)
				(type default)
			)
			(layer "B.SilkS")
		)
		(fp_line
			(start -0.67945 0.3048)
			(end -0.120396 0.3048)
			(stroke
				(width 0.1)
				(type default)
			)
			(layer "B.Fab")
		)
		(fp_line
			(start -0.120396 0.3048)
			(end -0.120396 0.2794)
			(stroke
				(width 0.1)
				(type default)
			)
			(layer "B.Fab")
		)
		(fp_line
			(start 0.12065 0.3048)
			(end 0.67945 0.3048)
			(stroke
				(width 0.1)
				(type default)
			)
			(layer "B.Fab")
		)
		(fp_line
			(start 0.67945 0.3048)
			(end 0.67945 -0.305054)
			(stroke
				(width 0.1)
				(type default)
			)
			(layer "B.Fab")
		)
		(fp_line
			(start -0.120396 0.2794)
			(end 0.12065 0.2794)
			(stroke
				(width 0.1)
				(type default)
			)
			(layer "B.Fab")
		)
		(fp_line
			(start 0.12065 0.2794)
			(end 0.12065 0.3048)
			(stroke
				(width 0.1)
				(type default)
			)
			(layer "B.Fab")
		)
		(fp_line
			(start -0.12065 -0.2794)
			(end -0.12065 -0.3048)
			(stroke
				(width 0.1)
				(type default)
			)
			(layer "B.Fab")
		)
		(fp_line
			(start 0.12065 -0.2794)
			(end -0.12065 -0.2794)
			(stroke
				(width 0.1)
				(type default)
			)
			(layer "B.Fab")
		)
		(fp_line
			(start -0.67945 -0.3048)
			(end -0.67945 0.3048)
			(stroke
				(width 0.1)
				(type default)
			)
			(layer "B.Fab")
		)
		(fp_line
			(start -0.12065 -0.3048)
			(end -0.67945 -0.3048)
			(stroke
				(width 0.1)
				(type default)
			)
			(layer "B.Fab")
		)
		(fp_line
			(start 0.12065 -0.305054)
			(end 0.12065 -0.2794)
			(stroke
				(width 0.1)
				(type default)
			)
			(layer "B.Fab")
		)
		(fp_line
			(start 0.67945 -0.305054)
			(end 0.12065 -0.305054)
			(stroke
				(width 0.1)
				(type default)
			)
			(layer "B.Fab")
		)
		(pad "1" smd circle
			(at 0.40005 0 90)
			(size 0 0)
			(layers "B.Cu" "B.Mask" "B.Paste")
			(net "PD_M_BMC_DDR4_ZQ")
		)
		(pad "2" smd circle
			(at -0.40005 0 90)
			(size 0 0)
			(layers "B.Cu" "B.Mask" "B.Paste")
			(net "GND")
		)
	)
)
